# T6G (Grand Teton) — schematic netlist excerpt (pin names and nets, part order shuffled) for the footprints in the layout excerpt that follows; sources: Cadence DE-HDL packaged netlist, KiCad conversion of 04192023_DAF0TMB3IC0_F0TG_MB_C_brd_V02_OCP.brd

R1446  Q_RES  4.7K 5% EMPTY  pkg 0201LF  page 276 : A = P1V8_CPU0_RT_1D ; B = JTAG_TCK_RT_CPU0_P0
C2319  Q_CAP  22UF 4V 20% X6S  pkg C0402  page 73 : A = PVDDCR_CPU0_P1 ; B = GND
C7013  Q_CAP  100UF 4V 20% X6S  pkg C0805  page 290 : A = P0V9_CPU0_RT1_2A ; B = GND
C998  Q_CAP  1UF 4V 20% X6S  pkg 0201  page 312 : A = P1V8_CPU0_RT3_1A ; B = GND

(kicad_pcb
	(version 20260206)
	(generator "pcbnew")
	(generator_version "10.0")
	(general
		(thickness 1.6)
		(legacy_teardrops no)
	)
	(paper "A4")
	(title_block
		(title "04192023_DAF0TMB3IC0_F0TG_MB_C_brd_V02_OCP.brd")
		(comment 1 "Grand Teton / footprints 6489-6492 of 8354")
	)
	(layers
		(0 "F.Cu" signal "TOP")
		(4 "In1.Cu" signal "GND")
		(6 "In2.Cu" signal "IN1")
		(8 "In3.Cu" signal "GND1")
		(10 "In4.Cu" signal "IN2")
		(12 "In5.Cu" signal "GND2")
		(14 "In6.Cu" signal "IN3")
		(16 "In7.Cu" signal "GND3")
		(18 "In8.Cu" signal "VCC")
		(20 "In9.Cu" signal "VCC1")
		(22 "In10.Cu" signal "GND4")
		(24 "In11.Cu" signal "IN4")
		(26 "In12.Cu" signal "GND5")
		(28 "In13.Cu" signal "IN5")
		(30 "In14.Cu" signal "GND6")
		(32 "In15.Cu" signal "IN6")
		(34 "In16.Cu" signal "GND7")
		(2 "B.Cu" signal "BOTTOM")
		(9 "F.Adhes" user "F.Adhesive")
		(11 "B.Adhes" user "B.Adhesive")
		(13 "F.Paste" user "Package Geometry/Pastemask Top")
		(15 "B.Paste" user "Package Geometry/Pastemask Bottom")
		(5 "F.SilkS" user "Ref Des/Silkscreen Top")
		(7 "B.SilkS" user "Ref Des/Silkscreen Bottom")
		(1 "F.Mask" user "Board Geometry/Soldermask Top")
		(3 "B.Mask" user "Board Geometry/Soldermask Bottom")
		(17 "Dwgs.User" user "User.Drawings")
		(19 "Cmts.User" user "User.Comments")
		(21 "Eco1.User" user "User.Eco1")
		(23 "Eco2.User" user "User.Eco2")
		(25 "Edge.Cuts" user "Board Geometry/Outline")
		(27 "Margin" user)
		(31 "F.CrtYd" user "Package Geometry/Place Bound Top")
		(29 "B.CrtYd" user "Package Geometry/Place Bound Bottom")
		(35 "F.Fab" user "Ref Des/Assembly Top")
		(33 "B.Fab" user "Ref Des/Assembly Bottom")
	)
	(footprint ""
		(layer "B.Cu")
		(at 105.196386 -248.479564)
		(property "Reference" "C2319"
			(at 0 0 0)
			(layer "B.SilkS")
			(hide yes)
			(effects
				(font
					(size 1.27 1.27)
				)
				(justify mirror)
			)
		)
		(property "Value" ""
			(at 0 0 0)
			(layer "B.Fab")
			(effects
				(font
					(size 1.27 1.27)
				)
				(justify mirror)
			)
		)
		(duplicate_pad_numbers_are_jumpers no)
		(fp_line
			(start -0.7874 -0.4064)
			(end -0.7874 0.4064)
			(stroke
				(width 0.1524)
				(type default)
			)
			(layer "B.SilkS")
		)
		(fp_line
			(start -0.7874 0.4064)
			(end 0.7874 0.4064)
			(stroke
				(width 0.1524)
				(type default)
			)
			(layer "B.SilkS")
		)
		(fp_line
			(start 0.7874 -0.4064)
			(end -0.7874 -0.4064)
			(stroke
				(width 0.1524)
				(type default)
			)
			(layer "B.SilkS")
		)
		(fp_line
			(start 0.7874 0.4064)
			(end 0.7874 -0.4064)
			(stroke
				(width 0.1524)
				(type default)
			)
			(layer "B.SilkS")
		)
		(fp_line
			(start -0.67945 -0.3048)
			(end -0.67945 0.3048)
			(stroke
				(width 0.1)
				(type default)
			)
			(layer "B.Fab")
		)
		(fp_line
			(start -0.67945 0.3048)
			(end -0.120396 0.3048)
			(stroke
				(width 0.1)
				(type default)
			)
			(layer "B.Fab")
		)
		(fp_line
			(start -0.12065 -0.3048)
			(end -0.67945 -0.3048)
			(stroke
				(width 0.1)
				(type default)
			)
			(layer "B.Fab")
		)
		(fp_line
			(start -0.12065 -0.2794)
			(end -0.12065 -0.3048)
			(stroke
				(width 0.1)
				(type default)
			)
			(layer "B.Fab")
		)
		(fp_line
			(start -0.120396 0.2794)
			(end 0.12065 0.2794)
			(stroke
				(width 0.1)
				(type default)
			)
			(layer "B.Fab")
		)
		(fp_line
			(start -0.120396 0.3048)
			(end -0.120396 0.2794)
			(stroke
				(width 0.1)
				(type default)
			)
			(layer "B.Fab")
		)
		(fp_line
			(start 0.12065 -0.305054)
			(end 0.12065 -0.2794)
			(stroke
				(width 0.1)
				(type default)
			)
			(layer "B.Fab")
		)
		(fp_line
			(start 0.12065 -0.2794)
			(end -0.12065 -0.2794)
			(stroke
				(width 0.1)
				(type default)
			)
			(layer "B.Fab")
		)
		(fp_line
			(start 0.12065 0.2794)
			(end 0.12065 0.3048)
			(stroke
				(width 0.1)
				(type default)
			)
			(layer "B.Fab")
		)
		(fp_line
			(start 0.12065 0.3048)
			(end 0.67945 0.3048)
			(stroke
				(width 0.1)
				(type default)
			)
			(layer "B.Fab")
		)
		(fp_line
			(start 0.67945 -0.305054)
			(end 0.12065 -0.305054)
			(stroke
				(width 0.1)
				(type default)
			)
			(layer "B.Fab")
		)
		(fp_line
			(start 0.67945 0.3048)
			(end 0.67945 -0.305054)
			(stroke
				(width 0.1)
				(type default)
			)
			(layer "B.Fab")
		)
		(pad "1" smd circle
			(at 0.40005 0 180)
			(size 0 0)
			(layers "B.Cu" "B.Mask" "B.Paste")
			(net "PVDDCR_CPU0_P1")
		)
		(pad "2" smd circle
			(at -0.40005 0 180)
			(size 0 0)
			(layers "B.Cu" "B.Mask" "B.Paste")
			(net "GND")
		)
	)
	(footprint ""
		(layer "B.Cu")
		(at 379.018546 -396.393162 -90)
		(property "Reference" "C998"
			(at 0 0 90)
			(layer "B.SilkS")
			(hide yes)
			(effects
				(font
					(size 1.27 1.27)
				)
				(justify mirror)
			)
		)
		(property "Value" ""
			(at 0 0 90)
			(layer "B.Fab")
			(effects
				(font
					(size 1.27 1.27)
				)
				(justify mirror)
			)
		)
		(duplicate_pad_numbers_are_jumpers no)
		(fp_line
			(start -0.299974 0.150114)
			(end 0.299974 0.150114)
			(stroke
				(width 0.1)
				(type default)
			)
			(layer "B.Fab")
		)
		(fp_line
			(start 0.299974 0.150114)
			(end 0.299974 -0.150114)
			(stroke
				(width 0.1)
				(type default)
			)
			(layer "B.Fab")
		)
		(fp_line
			(start -0.299974 -0.150114)
			(end -0.299974 0.150114)
			(stroke
				(width 0.1)
				(type default)
			)
			(layer "B.Fab")
		)
		(fp_line
			(start 0.299974 -0.150114)
			(end -0.299974 -0.150114)
			(stroke
				(width 0.1)
				(type default)
			)
			(layer "B.Fab")
		)
		(pad "1" smd rect
			(at 0.2667 0 90)
			(size 0.3048 0.381)
			(layers "B.Cu" "B.Mask" "B.Paste")
			(net "P1V8_CPU0_RT3_1A")
		)
		(pad "2" smd rect
			(at -0.2667 0 90)
			(size 0.3048 0.381)
			(layers "B.Cu" "B.Mask" "B.Paste")
			(net "GND")
		)
	)
	(footprint ""
		(layer "B.Cu")
		(at 334.099408 -389.97763)
		(property "Reference" "C7013"
			(at 0 0 0)
			(layer "B.SilkS")
			(hide yes)
			(effects
				(font
					(size 1.27 1.27)
				)
				(justify mirror)
			)
		)
		(property "Value" ""
			(at 0 0 0)
			(layer "B.Fab")
			(effects
				(font
					(size 1.27 1.27)
				)
				(justify mirror)
			)
		)
		(duplicate_pad_numbers_are_jumpers no)
		(fp_line
			(start -1.524 -0.762)
			(end -1.524 0.762)
			(stroke
				(width 0.1524)
				(type default)
			)
			(layer "B.SilkS")
		)
		(fp_line
			(start -1.524 0.762)
			(end 1.524 0.762)
			(stroke
				(width 0.1524)
				(type default)
			)
			(layer "B.SilkS")
		)
		(fp_line
			(start 1.524 -0.762)
			(end -1.524 -0.762)
			(stroke
				(width 0.1524)
				(type default)
			)
			(layer "B.SilkS")
		)
		(fp_line
			(start 1.524 0.762)
			(end 1.524 -0.762)
			(stroke
				(width 0.1524)
				(type default)
			)
			(layer "B.SilkS")
		)
		(fp_line
			(start -1.1049 -0.724916)
			(end 1.1049 -0.724916)
			(stroke
				(width 0.1)
				(type default)
			)
			(layer "B.Fab")
		)
		(fp_line
			(start -1.1049 0.724916)
			(end -1.1049 -0.724916)
			(stroke
				(width 0.1)
				(type default)
			)
			(layer "B.Fab")
		)
		(fp_line
			(start 1.1049 -0.724916)
			(end 1.1049 0.724916)
			(stroke
				(width 0.1)
				(type default)
			)
			(layer "B.Fab")
		)
		(fp_line
			(start 1.1049 0.724916)
			(end -1.1049 0.724916)
			(stroke
				(width 0.1)
				(type default)
			)
			(layer "B.Fab")
		)
		(pad "1" smd rect
			(at 0.889 0)
			(size 1.016 1.27)
			(layers "B.Cu" "B.Mask" "B.Paste")
			(net "P0V9_CPU0_RT1_2A")
		)
		(pad "2" smd rect
			(at -0.889 0)
			(size 1.016 1.27)
			(layers "B.Cu" "B.Mask" "B.Paste")
			(net "GND")
		)
	)
	(footprint ""
		(layer "B.Cu")
		(at 305.423316 -428.0916 180)
		(property "Reference" "R1446"
			(at 0 0 0)
			(layer "B.SilkS")
			(hide yes)
			(effects
				(font
					(size 1.27 1.27)
				)
				(justify mirror)
			)
		)
		(property "Value" ""
			(at 0 0 0)
			(layer "B.Fab")
			(effects
				(font
					(size 1.27 1.27)
				)
				(justify mirror)
			)
		)
		(duplicate_pad_numbers_are_jumpers no)
		(fp_line
			(start 0.32512 0.175006)
			(end 0.32512 -0.175006)
			(stroke
				(width 0.1)
				(type default)
			)
			(layer "B.Fab")
		)
		(fp_line
			(start 0.32512 -0.175006)
			(end -0.32512 -0.175006)
			(stroke
				(width 0.1)
				(type default)
			)
			(layer "B.Fab")
		)
		(fp_line
			(start -0.32512 0.175006)
			(end 0.32512 0.175006)
			(stroke
				(width 0.1)
				(type default)
			)
			(layer "B.Fab")
		)
		(fp_line
			(start -0.32512 -0.175006)
			(end -0.32512 0.175006)
			(stroke
				(width 0.1)
				(type default)
			)
			(layer "B.Fab")
		)
		(pad "1" smd rect
			(at 0.2667 0)
			(size 0.3048 0.381)
			(layers "B.Cu" "B.Mask" "B.Paste")
			(net "P1V8_CPU0_RT_1D")
		)
		(pad "2" smd rect
			(at -0.2667 0 180)
			(size 0.3048 0.381)
			(layers "B.Cu" "B.Mask" "B.Paste")
			(net "JTAG_TCK_RT_CPU0_P0")
		)
	)
)
